# TIMECARD (Time Appliance Project (Time Card)) — schematic netlist excerpt (pin names and nets, part order shuffled) for the footprints in the layout excerpt that follows; sources: Cadence DE-HDL packaged netlist, KiCad conversion of R4006-B0001-02_R01.brd

C149  CAPACITOR  0.1UF 10V 10%  pkg SMC_0402R_H022  page 14 : \1\ = XP3R3V_FPGA ; \2\ = SG
C153  CAPACITOR  0.1UF 10V 10%  pkg SMC_0402R_H022  page 14 : \1\ = XP3R3V_FPGA ; \2\ = SG

(kicad_pcb
	(version 20260206)
	(generator "pcbnew")
	(generator_version "10.0")
	(general
		(thickness 1.6)
		(legacy_teardrops no)
	)
	(paper "A4")
	(title_block
		(title "timecard-production-celestica-r4006 — R4006-B0001-02_R01.brd")
		(comment 1 "Time Appliance Project (Time Card) / footprints 806-807 of 1113")
	)
	(layers
		(0 "F.Cu" signal "TOP")
		(4 "In1.Cu" signal "L02_GND1")
		(6 "In2.Cu" signal "L03_SIG1")
		(8 "In3.Cu" signal "L04_GND2")
		(10 "In4.Cu" signal "L05_VCC1")
		(12 "In5.Cu" signal "L06_VCC2")
		(14 "In6.Cu" signal "L07_GND3")
		(16 "In7.Cu" signal "L08_SIG2")
		(18 "In8.Cu" signal "L09_GND4")
		(2 "B.Cu" signal "BOTTOM")
		(9 "F.Adhes" user "F.Adhesive")
		(11 "B.Adhes" user "B.Adhesive")
		(13 "F.Paste" user "Package Geometry/Pastemask Top")
		(15 "B.Paste" user "Package Geometry/Pastemask Bottom")
		(5 "F.SilkS" user "Ref Des/Silkscreen Top")
		(7 "B.SilkS" user "Ref Des/Silkscreen Bottom")
		(1 "F.Mask" user "Board Geometry/Soldermask Top")
		(3 "B.Mask" user "Board Geometry/Soldermask Bottom")
		(17 "Dwgs.User" user "User.Drawings")
		(19 "Cmts.User" user "User.Comments")
		(21 "Eco1.User" user "User.Eco1")
		(23 "Eco2.User" user "User.Eco2")
		(25 "Edge.Cuts" user "Board Geometry/Outline")
		(27 "Margin" user)
		(31 "F.CrtYd" user "Package Geometry/Place Bound Top")
		(29 "B.CrtYd" user "Package Geometry/Place Bound Bottom")
		(35 "F.Fab" user "Ref Des/Assembly Top")
		(33 "B.Fab" user "Ref Des/Assembly Bottom")
	)
	(footprint ""
		(layer "B.Cu")
		(at 104.34701 -49.823116)
		(property "Reference" "C153"
			(at -0.20701 -0.945134 0)
			(unlocked yes)
			(layer "B.SilkS")
			(effects
				(font
					(size 0.635 0.4064)
					(thickness 0.1524)
				)
				(justify mirror)
			)
		)
		(property "Value" "VAL*"
			(at 0 3.718306 0)
			(unlocked yes)
			(layer "B.Fab")
			(hide yes)
			(effects
				(font
					(size 0.7874 0.5842)
					(thickness 0.127)
				)
				(justify mirror)
			)
		)
		(property "Device Type" "CAPACITOR-G105-0B104-CK,0.1UF,A"
			(at 0 1.432306 0)
			(unlocked yes)
			(layer "B.Fab")
			(hide yes)
			(effects
				(font
					(size 0.7874 0.5842)
					(thickness 0.127)
				)
				(justify mirror)
			)
		)
		(property "User Part Number" "PARTNUM*"
			(at 0 2.575306 0)
			(unlocked yes)
			(layer "Cmts.User")
			(hide yes)
			(effects
				(font
					(size 0.7874 0.5842)
					(thickness 0.127)
				)
				(justify mirror)
			)
		)
		(property "Tolerance" "TOL*"
			(at 0 4.861306 0)
			(unlocked yes)
			(layer "Cmts.User")
			(hide yes)
			(effects
				(font
					(size 0.7874 0.5842)
					(thickness 0.127)
				)
				(justify mirror)
			)
		)
		(duplicate_pad_numbers_are_jumpers no)
		(fp_line
			(start -0.970026 -0.4699)
			(end -0.970026 0.4699)
			(stroke
				(width 0.1)
				(type default)
			)
			(layer "B.SilkS")
		)
		(fp_line
			(start -0.970026 0.4699)
			(end 0.970026 0.4699)
			(stroke
				(width 0.1)
				(type default)
			)
			(layer "B.SilkS")
		)
		(fp_line
			(start 0.970026 -0.4699)
			(end -0.970026 -0.4699)
			(stroke
				(width 0.1)
				(type default)
			)
			(layer "B.SilkS")
		)
		(fp_line
			(start 0.970026 0.4699)
			(end 0.970026 -0.4699)
			(stroke
				(width 0.1)
				(type default)
			)
			(layer "B.SilkS")
		)
		(fp_poly
			(pts
				(xy 0.970026 0.4699) (xy -0.970026 0.4699) (xy -0.970026 -0.4699) (xy 0.970026 -0.4699)
			)
			(stroke
				(width 0)
				(type default)
			)
			(fill no)
			(layer "B.CrtYd")
		)
		(fp_line
			(start -0.508 -0.3048)
			(end -0.508 0.3048)
			(stroke
				(width 0.1)
				(type default)
			)
			(layer "B.Fab")
		)
		(fp_line
			(start -0.508 0.3048)
			(end 0.508 0.3048)
			(stroke
				(width 0.1)
				(type default)
			)
			(layer "B.Fab")
		)
		(fp_line
			(start 0.508 -0.3048)
			(end -0.508 -0.3048)
			(stroke
				(width 0.1)
				(type default)
			)
			(layer "B.Fab")
		)
		(fp_line
			(start 0.508 0.3048)
			(end 0.508 -0.3048)
			(stroke
				(width 0.1)
				(type default)
			)
			(layer "B.Fab")
		)
		(pad "1" smd circle
			(at 0.500126 0 180)
			(size 0.635 0.635)
			(layers "B.Cu" "B.Mask" "B.Paste")
			(net "XP3R3V_FPGA")
		)
		(pad "2" smd circle
			(at -0.500126 0 180)
			(size 0.635 0.635)
			(layers "B.Cu" "B.Mask" "B.Paste")
			(net "SG")
		)
	)
	(footprint ""
		(layer "B.Cu")
		(at 109.22 -51.0032 -90)
		(property "Reference" "C149"
			(at -0.9398 -0.98425 270)
			(unlocked yes)
			(layer "B.SilkS")
			(effects
				(font
					(size 0.635 0.4064)
					(thickness 0.1524)
				)
				(justify mirror)
			)
		)
		(property "Value" "VAL*"
			(at -0.0762 2.067306 270)
			(unlocked yes)
			(layer "B.Fab")
			(hide yes)
			(effects
				(font
					(size 0.7874 0.5842)
					(thickness 0.1524)
				)
				(justify mirror)
			)
		)
		(property "Device Type" "CAPACITOR-G105-0B104-CK,0.1UF,A"
			(at -0.0508 1.127506 270)
			(unlocked yes)
			(layer "B.Fab")
			(hide yes)
			(effects
				(font
					(size 0.7874 0.5842)
					(thickness 0.1524)
				)
				(justify mirror)
			)
		)
		(property "User Part Number" "PARTNUM*"
			(at -0.1016 4.023106 270)
			(unlocked yes)
			(layer "Cmts.User")
			(hide yes)
			(effects
				(font
					(size 0.7874 0.5842)
					(thickness 0.1524)
				)
				(justify mirror)
			)
		)
		(property "Tolerance" "TOL*"
			(at -0.0762 3.032506 270)
			(unlocked yes)
			(layer "Cmts.User")
			(hide yes)
			(effects
				(font
					(size 0.7874 0.5842)
					(thickness 0.1524)
				)
				(justify mirror)
			)
		)
		(duplicate_pad_numbers_are_jumpers no)
		(fp_line
			(start -1.143 0.5588)
			(end -1.143 -0.5588)
			(stroke
				(width 0.1)
				(type default)
			)
			(layer "B.SilkS")
		)
		(fp_line
			(start 1.143 0.5588)
			(end -1.143 0.5588)
			(stroke
				(width 0.1)
				(type default)
			)
			(layer "B.SilkS")
		)
		(fp_line
			(start -1.143 -0.5588)
			(end 1.143 -0.5588)
			(stroke
				(width 0.1)
				(type default)
			)
			(layer "B.SilkS")
		)
		(fp_line
			(start 1.143 -0.5588)
			(end 1.143 0.5588)
			(stroke
				(width 0.1)
				(type default)
			)
			(layer "B.SilkS")
		)
		(fp_rect
			(start 1.143 0.5588)
			(end -1.143 -0.5588)
			(stroke
				(width 0)
				(type default)
			)
			(fill no)
			(layer "B.CrtYd")
		)
		(fp_line
			(start -0.508 0.3048)
			(end -0.508 -0.3048)
			(stroke
				(width 0.1)
				(type default)
			)
			(layer "B.Fab")
		)
		(fp_line
			(start 0.508 0.3048)
			(end -0.508 0.3048)
			(stroke
				(width 0.1)
				(type default)
			)
			(layer "B.Fab")
		)
		(fp_line
			(start -0.508 -0.3048)
			(end 0.508 -0.3048)
			(stroke
				(width 0.1)
				(type default)
			)
			(layer "B.Fab")
		)
		(fp_line
			(start 0.508 -0.3048)
			(end 0.508 0.3048)
			(stroke
				(width 0.1)
				(type default)
			)
			(layer "B.Fab")
		)
		(pad "1" smd rect
			(at 0.5334 0 90)
			(size 0.7112 0.6096)
			(layers "B.Cu" "B.Mask" "B.Paste")
			(net "XP3R3V_FPGA")
		)
		(pad "2" smd rect
			(at -0.5334 0 90)
			(size 0.7112 0.6096)
			(layers "B.Cu" "B.Mask" "B.Paste")
			(net "SG")
		)
		(zone
			(layer "B.Cu")
			(hatch none 0.5)
			(connect_pads
				(clearance 0)
			)
			(min_thickness 0.25)
			(keepout
				(tracks allowed)
				(vias not_allowed)
				(pads allowed)
				(copperpour not_allowed)
				(footprints allowed)
			)
			(placement
				(enabled no)
				(sheetname "")
			)
			(fill
				(thermal_gap 0.5)
				(thermal_bridge_width 0.5)
				(island_removal_mode 0)
			)
			(polygon
				(pts
					(xy 108.9152 -50.927) (xy 109.5248 -50.927) (xy 109.5248 -51.0794) (xy 108.9152 -51.0794)
				)
			)
		)
	)
)
